# T6G (Grand Teton) — schematic netlist excerpt (pin names and nets, part order shuffled) for the footprints in the layout excerpt that follows; sources: Cadence DE-HDL packaged netlist, KiCad conversion of 04192023_DAF0TMB3IC0_F0TG_MB_C_brd_V02_OCP.brd

R1122  Q_RES  4.7K 5% CHIP  pkg 0201LF  page 309 : A = P1V8_CPU0_RT_1D ; B = MODE_RT_CPU0_P3
R1314  Q_RES  4.7K 5% EMPTY  pkg 0402LF  page 83 : A = E1S_0_P12V_EN ; B = P3V3_AUX
PR147  Q_RES  10K 1% CHIP  pkg 0402LF  page 226 : A = PVDD18_S5_P1_FB ; B = PVDD18_SS_P1_RGND

(kicad_pcb
	(version 20260206)
	(generator "pcbnew")
	(generator_version "10.0")
	(general
		(thickness 1.6)
		(legacy_teardrops no)
	)
	(paper "A4")
	(title_block
		(title "04192023_DAF0TMB3IC0_F0TG_MB_C_brd_V02_OCP.brd")
		(comment 1 "Grand Teton / footprints 809-811 of 8354")
	)
	(layers
		(0 "F.Cu" signal "TOP")
		(4 "In1.Cu" signal "GND")
		(6 "In2.Cu" signal "IN1")
		(8 "In3.Cu" signal "GND1")
		(10 "In4.Cu" signal "IN2")
		(12 "In5.Cu" signal "GND2")
		(14 "In6.Cu" signal "IN3")
		(16 "In7.Cu" signal "GND3")
		(18 "In8.Cu" signal "VCC")
		(20 "In9.Cu" signal "VCC1")
		(22 "In10.Cu" signal "GND4")
		(24 "In11.Cu" signal "IN4")
		(26 "In12.Cu" signal "GND5")
		(28 "In13.Cu" signal "IN5")
		(30 "In14.Cu" signal "GND6")
		(32 "In15.Cu" signal "IN6")
		(34 "In16.Cu" signal "GND7")
		(2 "B.Cu" signal "BOTTOM")
		(9 "F.Adhes" user "F.Adhesive")
		(11 "B.Adhes" user "B.Adhesive")
		(13 "F.Paste" user "Package Geometry/Pastemask Top")
		(15 "B.Paste" user "Package Geometry/Pastemask Bottom")
		(5 "F.SilkS" user "Ref Des/Silkscreen Top")
		(7 "B.SilkS" user "Ref Des/Silkscreen Bottom")
		(1 "F.Mask" user "Board Geometry/Soldermask Top")
		(3 "B.Mask" user "Board Geometry/Soldermask Bottom")
		(17 "Dwgs.User" user "User.Drawings")
		(19 "Cmts.User" user "User.Comments")
		(21 "Eco1.User" user "User.Eco1")
		(23 "Eco2.User" user "User.Eco2")
		(25 "Edge.Cuts" user "Board Geometry/Outline")
		(27 "Margin" user)
		(31 "F.CrtYd" user "Package Geometry/Place Bound Top")
		(29 "B.CrtYd" user "Package Geometry/Place Bound Bottom")
		(35 "F.Fab" user "Ref Des/Assembly Top")
		(33 "B.Fab" user "Ref Des/Assembly Bottom")
	)
	(footprint ""
		(layer "F.Cu")
		(at 200.952608 -113.625376 180)
		(property "Reference" "R1314"
			(at 0 0 180)
			(layer "F.SilkS")
			(hide yes)
			(effects
				(font
					(size 1.27 1.27)
				)
			)
		)
		(property "Value" ""
			(at 0 0 180)
			(layer "F.Fab")
			(effects
				(font
					(size 1.27 1.27)
				)
			)
		)
		(duplicate_pad_numbers_are_jumpers no)
		(fp_line
			(start 0.7874 0.4064)
			(end -0.7874 0.4064)
			(stroke
				(width 0.1524)
				(type default)
			)
			(layer "F.SilkS")
		)
		(fp_line
			(start 0.7874 -0.4064)
			(end 0.7874 0.4064)
			(stroke
				(width 0.1524)
				(type default)
			)
			(layer "F.SilkS")
		)
		(fp_line
			(start -0.7874 0.4064)
			(end -0.7874 -0.4064)
			(stroke
				(width 0.1524)
				(type default)
			)
			(layer "F.SilkS")
		)
		(fp_line
			(start -0.7874 -0.4064)
			(end 0.7874 -0.4064)
			(stroke
				(width 0.1524)
				(type default)
			)
			(layer "F.SilkS")
		)
		(fp_line
			(start 0.67945 0.3048)
			(end 0.120396 0.3048)
			(stroke
				(width 0.1)
				(type default)
			)
			(layer "F.Fab")
		)
		(fp_line
			(start 0.67945 -0.3048)
			(end 0.67945 0.3048)
			(stroke
				(width 0.1)
				(type default)
			)
			(layer "F.Fab")
		)
		(fp_line
			(start 0.12065 -0.2794)
			(end 0.12065 -0.3048)
			(stroke
				(width 0.1)
				(type default)
			)
			(layer "F.Fab")
		)
		(fp_line
			(start 0.12065 -0.3048)
			(end 0.67945 -0.3048)
			(stroke
				(width 0.1)
				(type default)
			)
			(layer "F.Fab")
		)
		(fp_line
			(start 0.120396 0.3048)
			(end 0.120396 0.2794)
			(stroke
				(width 0.1)
				(type default)
			)
			(layer "F.Fab")
		)
		(fp_line
			(start 0.120396 0.2794)
			(end -0.12065 0.2794)
			(stroke
				(width 0.1)
				(type default)
			)
			(layer "F.Fab")
		)
		(fp_line
			(start -0.12065 0.3048)
			(end -0.67945 0.3048)
			(stroke
				(width 0.1)
				(type default)
			)
			(layer "F.Fab")
		)
		(fp_line
			(start -0.12065 0.2794)
			(end -0.12065 0.3048)
			(stroke
				(width 0.1)
				(type default)
			)
			(layer "F.Fab")
		)
		(fp_line
			(start -0.12065 -0.2794)
			(end 0.12065 -0.2794)
			(stroke
				(width 0.1)
				(type default)
			)
			(layer "F.Fab")
		)
		(fp_line
			(start -0.12065 -0.305054)
			(end -0.12065 -0.2794)
			(stroke
				(width 0.1)
				(type default)
			)
			(layer "F.Fab")
		)
		(fp_line
			(start -0.67945 0.3048)
			(end -0.67945 -0.305054)
			(stroke
				(width 0.1)
				(type default)
			)
			(layer "F.Fab")
		)
		(fp_line
			(start -0.67945 -0.305054)
			(end -0.12065 -0.305054)
			(stroke
				(width 0.1)
				(type default)
			)
			(layer "F.Fab")
		)
		(pad "1" smd circle
			(at -0.40005 0 180)
			(size 0 0)
			(layers "F.Cu" "F.Mask" "F.Paste")
			(net "E1S_0_P12V_EN")
		)
		(pad "2" smd circle
			(at 0.40005 0 180)
			(size 0 0)
			(layers "F.Cu" "F.Mask" "F.Paste")
			(net "P3V3_AUX")
		)
	)
	(footprint ""
		(layer "F.Cu")
		(at 72.466454 -148.635212 179.946)
		(property "Reference" "PR147"
			(at 0 0 179.946)
			(layer "F.SilkS")
			(hide yes)
			(effects
				(font
					(size 1.27 1.27)
				)
			)
		)
		(property "Value" ""
			(at 0 0 179.946)
			(layer "F.Fab")
			(effects
				(font
					(size 1.27 1.27)
				)
			)
		)
		(duplicate_pad_numbers_are_jumpers no)
		(fp_line
			(start 0.787525 -0.40638)
			(end 0.787275 0.40642)
			(stroke
				(width 0.1524)
				(type default)
			)
			(layer "F.SilkS")
		)
		(fp_line
			(start 0.787275 0.40642)
			(end -0.787525 0.40638)
			(stroke
				(width 0.1524)
				(type default)
			)
			(layer "F.SilkS")
		)
		(fp_line
			(start -0.787275 -0.40642)
			(end 0.787525 -0.40638)
			(stroke
				(width 0.1524)
				(type default)
			)
			(layer "F.SilkS")
		)
		(fp_line
			(start -0.787525 0.40638)
			(end -0.787275 -0.40642)
			(stroke
				(width 0.1524)
				(type default)
			)
			(layer "F.SilkS")
		)
		(fp_line
			(start 0.679417 -0.304678)
			(end 0.679484 0.304922)
			(stroke
				(width 0.1)
				(type default)
			)
			(layer "F.Fab")
		)
		(fp_line
			(start 0.679484 0.304922)
			(end 0.120429 0.304687)
			(stroke
				(width 0.1)
				(type default)
			)
			(layer "F.Fab")
		)
		(fp_line
			(start 0.120641 -0.279514)
			(end 0.120617 -0.304914)
			(stroke
				(width 0.1)
				(type default)
			)
			(layer "F.Fab")
		)
		(fp_line
			(start 0.120617 -0.304914)
			(end 0.679417 -0.304678)
			(stroke
				(width 0.1)
				(type default)
			)
			(layer "F.Fab")
		)
		(fp_line
			(start 0.120429 0.304687)
			(end 0.120405 0.279287)
			(stroke
				(width 0.1)
				(type default)
			)
			(layer "F.Fab")
		)
		(fp_line
			(start 0.120405 0.279287)
			(end -0.120641 0.279514)
			(stroke
				(width 0.1)
				(type default)
			)
			(layer "F.Fab")
		)
		(fp_line
			(start -0.120659 -0.279286)
			(end 0.120641 -0.279514)
			(stroke
				(width 0.1)
				(type default)
			)
			(layer "F.Fab")
		)
		(fp_line
			(start -0.120683 -0.30494)
			(end -0.120659 -0.279286)
			(stroke
				(width 0.1)
				(type default)
			)
			(layer "F.Fab")
		)
		(fp_line
			(start -0.120617 0.304914)
			(end -0.679417 0.304678)
			(stroke
				(width 0.1)
				(type default)
			)
			(layer "F.Fab")
		)
		(fp_line
			(start -0.120641 0.279514)
			(end -0.120617 0.304914)
			(stroke
				(width 0.1)
				(type default)
			)
			(layer "F.Fab")
		)
		(fp_line
			(start -0.679484 -0.305176)
			(end -0.120683 -0.30494)
			(stroke
				(width 0.1)
				(type default)
			)
			(layer "F.Fab")
		)
		(fp_line
			(start -0.679417 0.304678)
			(end -0.679484 -0.305176)
			(stroke
				(width 0.1)
				(type default)
			)
			(layer "F.Fab")
		)
		(pad "1" smd circle
			(at -0.40005 0 179.946)
			(size 0 0)
			(layers "F.Cu" "F.Mask" "F.Paste")
			(net "PVDD18_S5_P1_FB")
		)
		(pad "2" smd circle
			(at 0.40005 0 179.946)
			(size 0 0)
			(layers "F.Cu" "F.Mask" "F.Paste")
			(net "PVDD18_SS_P1_RGND")
		)
	)
	(footprint ""
		(layer "F.Cu")
		(at 368.600736 -403.818852 -90)
		(property "Reference" "R1122"
			(at 0 0 270)
			(layer "F.SilkS")
			(hide yes)
			(effects
				(font
					(size 1.27 1.27)
				)
			)
		)
		(property "Value" ""
			(at 0 0 270)
			(layer "F.Fab")
			(effects
				(font
					(size 1.27 1.27)
				)
			)
		)
		(duplicate_pad_numbers_are_jumpers no)
		(fp_line
			(start -0.32512 0.175006)
			(end -0.32512 -0.175006)
			(stroke
				(width 0.1)
				(type default)
			)
			(layer "F.Fab")
		)
		(fp_line
			(start 0.32512 0.175006)
			(end -0.32512 0.175006)
			(stroke
				(width 0.1)
				(type default)
			)
			(layer "F.Fab")
		)
		(fp_line
			(start -0.32512 -0.175006)
			(end 0.32512 -0.175006)
			(stroke
				(width 0.1)
				(type default)
			)
			(layer "F.Fab")
		)
		(fp_line
			(start 0.32512 -0.175006)
			(end 0.32512 0.175006)
			(stroke
				(width 0.1)
				(type default)
			)
			(layer "F.Fab")
		)
		(pad "1" smd rect
			(at -0.2667 0 270)
			(size 0.3048 0.381)
			(layers "F.Cu" "F.Mask" "F.Paste")
			(net "P1V8_CPU0_RT_1D")
		)
		(pad "2" smd rect
			(at 0.2667 0 90)
			(size 0.3048 0.381)
			(layers "F.Cu" "F.Mask" "F.Paste")
			(net "MODE_RT_CPU0_P3")
		)
	)
)
